G04*
G04 #@! TF.GenerationSoftware,Altium Limited,Altium Designer,23.0.1 (38)*
G04*
G04 Layer_Color=65535*
%FSLAX44Y44*%
%MOMM*%
G71*
G04*
G04 #@! TF.SameCoordinates,9A23C038-B079-480F-8166-AFFB5740F5AE*
G04*
G04*
G04 #@! TF.FilePolarity,Positive*
G04*
G01*
G75*
%ADD10C,0.1778*%
%ADD11C,0.1524*%
%ADD12C,0.0762*%
%ADD13C,0.1780*%
%ADD14R,0.1010X0.0691*%
%ADD15R,0.4500X3.4755*%
%ADD16R,1.1684X1.3970*%
%ADD17R,14.1000X4.3000*%
G36*
X470077Y15876D02*
X466431D01*
Y17060D01*
X470077D01*
Y15876D01*
D02*
G37*
G36*
X497679Y13000D02*
X496365D01*
X491335Y20528D01*
Y13000D01*
X490116D01*
Y22599D01*
X491418D01*
X496460Y15059D01*
Y22599D01*
X497679D01*
Y13000D01*
D02*
G37*
G36*
X445563D02*
X444250D01*
X439219Y20528D01*
Y13000D01*
X438000D01*
Y22599D01*
X439302D01*
X444344Y15059D01*
Y22599D01*
X445563D01*
Y13000D01*
D02*
G37*
G36*
X512640Y13000D02*
X511421D01*
Y21037D01*
X508628Y13000D01*
X507480D01*
X504710Y21167D01*
Y13000D01*
X503491D01*
Y22599D01*
X505373D01*
X507657Y15805D01*
Y15793D01*
X507669Y15770D01*
X507693Y15711D01*
X507705Y15651D01*
X507740Y15568D01*
X507764Y15486D01*
X507835Y15273D01*
X507906Y15048D01*
X507989Y14811D01*
X508060Y14586D01*
X508119Y14385D01*
Y14397D01*
X508131Y14409D01*
X508143Y14444D01*
X508154Y14480D01*
X508166Y14539D01*
X508190Y14598D01*
X508214Y14681D01*
X508249Y14776D01*
X508273Y14870D01*
X508320Y14988D01*
X508355Y15119D01*
X508403Y15249D01*
X508509Y15568D01*
X508628Y15924D01*
X510936Y22599D01*
X512640D01*
Y13000D01*
D02*
G37*
G36*
X480623Y13000D02*
X479404D01*
Y21037D01*
X476610Y13000D01*
X475462D01*
X472692Y21167D01*
Y13000D01*
X471473D01*
Y22599D01*
X473355D01*
X475640Y15805D01*
Y15793D01*
X475652Y15770D01*
X475675Y15711D01*
X475687Y15651D01*
X475723Y15568D01*
X475746Y15486D01*
X475817Y15273D01*
X475888Y15048D01*
X475971Y14811D01*
X476042Y14586D01*
X476101Y14385D01*
Y14397D01*
X476113Y14409D01*
X476125Y14444D01*
X476137Y14480D01*
X476149Y14539D01*
X476172Y14598D01*
X476196Y14681D01*
X476232Y14776D01*
X476255Y14870D01*
X476303Y14988D01*
X476338Y15119D01*
X476385Y15249D01*
X476492Y15568D01*
X476610Y15924D01*
X478918Y22599D01*
X480623D01*
Y13000D01*
D02*
G37*
G36*
X568627Y13000D02*
X567313D01*
X563596Y22599D01*
X564981D01*
X567467Y15616D01*
Y15604D01*
X567478Y15580D01*
X567502Y15533D01*
X567514Y15474D01*
X567549Y15403D01*
X567573Y15308D01*
X567644Y15107D01*
X567727Y14858D01*
X567810Y14598D01*
X567893Y14326D01*
X567976Y14042D01*
Y14053D01*
X567987Y14077D01*
X567999Y14124D01*
X568011Y14172D01*
X568035Y14243D01*
X568058Y14326D01*
X568129Y14527D01*
X568200Y14776D01*
X568295Y15036D01*
X568390Y15320D01*
X568496Y15616D01*
X571088Y22599D01*
X572379D01*
X568627Y13000D01*
D02*
G37*
G36*
X542361Y17048D02*
Y17036D01*
Y16989D01*
Y16906D01*
Y16811D01*
X542350Y16693D01*
Y16551D01*
X542338Y16385D01*
X542326Y16220D01*
X542279Y15853D01*
X542220Y15474D01*
X542137Y15095D01*
X542089Y14918D01*
X542030Y14752D01*
Y14740D01*
X542018Y14716D01*
X541995Y14669D01*
X541971Y14610D01*
X541924Y14539D01*
X541876Y14456D01*
X541758Y14255D01*
X541592Y14042D01*
X541391Y13805D01*
X541142Y13580D01*
X541000Y13474D01*
X540846Y13367D01*
X540835D01*
X540811Y13343D01*
X540764Y13320D01*
X540693Y13284D01*
X540610Y13249D01*
X540503Y13201D01*
X540385Y13154D01*
X540243Y13107D01*
X540089Y13047D01*
X539923Y13000D01*
X539734Y12953D01*
X539544Y12917D01*
X539320Y12882D01*
X539095Y12858D01*
X538858Y12846D01*
X538598Y12834D01*
X538467D01*
X538373Y12846D01*
X538254D01*
X538124Y12858D01*
X537982Y12870D01*
X537816Y12894D01*
X537461Y12953D01*
X537094Y13024D01*
X536727Y13142D01*
X536384Y13296D01*
X536372D01*
X536349Y13320D01*
X536301Y13343D01*
X536242Y13379D01*
X536171Y13426D01*
X536100Y13485D01*
X535911Y13639D01*
X535709Y13829D01*
X535508Y14053D01*
X535319Y14326D01*
X535165Y14633D01*
Y14645D01*
X535153Y14681D01*
X535130Y14728D01*
X535106Y14799D01*
X535082Y14882D01*
X535059Y15000D01*
X535023Y15119D01*
X534987Y15273D01*
X534952Y15426D01*
X534928Y15616D01*
X534893Y15817D01*
X534869Y16030D01*
X534845Y16255D01*
X534822Y16504D01*
X534810Y16764D01*
Y17048D01*
Y22599D01*
X536076D01*
Y17060D01*
Y17048D01*
Y17001D01*
Y16941D01*
Y16859D01*
X536088Y16752D01*
Y16634D01*
X536100Y16504D01*
Y16362D01*
X536136Y16054D01*
X536171Y15758D01*
X536230Y15462D01*
X536266Y15332D01*
X536301Y15213D01*
Y15202D01*
X536313Y15190D01*
X536349Y15119D01*
X536408Y15012D01*
X536491Y14882D01*
X536597Y14728D01*
X536739Y14574D01*
X536905Y14432D01*
X537106Y14302D01*
X537118D01*
X537130Y14290D01*
X537165Y14278D01*
X537213Y14255D01*
X537331Y14195D01*
X537497Y14148D01*
X537698Y14089D01*
X537935Y14030D01*
X538195Y13994D01*
X538491Y13982D01*
X538621D01*
X538716Y13994D01*
X538834Y14006D01*
X538965Y14018D01*
X539118Y14030D01*
X539272Y14065D01*
X539604Y14136D01*
X539935Y14243D01*
X540089Y14314D01*
X540231Y14409D01*
X540373Y14503D01*
X540491Y14610D01*
X540503Y14622D01*
X540515Y14645D01*
X540551Y14681D01*
X540586Y14740D01*
X540633Y14811D01*
X540681Y14906D01*
X540740Y15024D01*
X540799Y15154D01*
X540846Y15308D01*
X540906Y15486D01*
X540953Y15687D01*
X541000Y15912D01*
X541036Y16160D01*
X541071Y16433D01*
X541083Y16729D01*
X541095Y17060D01*
Y22599D01*
X542361D01*
Y17048D01*
D02*
G37*
G36*
X485357Y22623D02*
X485440D01*
X485547Y22611D01*
X485653Y22587D01*
X485772Y22576D01*
X486032Y22517D01*
X486328Y22422D01*
X486624Y22292D01*
X486778Y22221D01*
X486920Y22126D01*
X486932D01*
X486955Y22102D01*
X486991Y22078D01*
X487050Y22031D01*
X487192Y21913D01*
X487358Y21759D01*
X487547Y21546D01*
X487748Y21297D01*
X487938Y21013D01*
X488103Y20682D01*
Y20670D01*
X488115Y20635D01*
X488139Y20587D01*
X488163Y20516D01*
X488198Y20410D01*
X488234Y20291D01*
X488269Y20161D01*
X488305Y19995D01*
X488340Y19818D01*
X488376Y19617D01*
X488411Y19392D01*
X488447Y19155D01*
X488470Y18894D01*
X488494Y18611D01*
X488506Y18303D01*
Y17983D01*
Y17960D01*
Y17900D01*
Y17806D01*
Y17675D01*
X488494Y17522D01*
X488482Y17344D01*
X488470Y17143D01*
X488459Y16930D01*
X488435Y16705D01*
X488411Y16468D01*
X488340Y15971D01*
X488234Y15497D01*
X488175Y15273D01*
X488103Y15059D01*
Y15048D01*
X488080Y15012D01*
X488056Y14953D01*
X488032Y14882D01*
X487985Y14787D01*
X487938Y14681D01*
X487808Y14444D01*
X487630Y14172D01*
X487429Y13900D01*
X487192Y13639D01*
X487050Y13521D01*
X486908Y13402D01*
X486896Y13391D01*
X486872Y13379D01*
X486825Y13355D01*
X486766Y13320D01*
X486695Y13272D01*
X486600Y13225D01*
X486506Y13177D01*
X486387Y13118D01*
X486257Y13071D01*
X486115Y13012D01*
X485795Y12929D01*
X485452Y12858D01*
X485263Y12846D01*
X485061Y12834D01*
X484955D01*
X484872Y12846D01*
X484777Y12858D01*
X484671Y12870D01*
X484541Y12882D01*
X484411Y12917D01*
X484115Y12988D01*
X483819Y13095D01*
X483665Y13166D01*
X483511Y13249D01*
X483369Y13343D01*
X483227Y13450D01*
X483215Y13462D01*
X483191Y13474D01*
X483156Y13521D01*
X483108Y13568D01*
X483061Y13627D01*
X482990Y13710D01*
X482931Y13805D01*
X482860Y13911D01*
X482777Y14030D01*
X482706Y14160D01*
X482635Y14302D01*
X482564Y14456D01*
X482505Y14633D01*
X482458Y14811D01*
X482410Y15012D01*
X482375Y15213D01*
X483511Y15308D01*
Y15296D01*
X483523Y15273D01*
Y15237D01*
X483535Y15178D01*
X483582Y15036D01*
X483629Y14870D01*
X483712Y14681D01*
X483807Y14491D01*
X483913Y14314D01*
X484055Y14160D01*
X484079Y14148D01*
X484126Y14101D01*
X484221Y14053D01*
X484339Y13982D01*
X484482Y13923D01*
X484671Y13864D01*
X484872Y13817D01*
X485097Y13805D01*
X485192D01*
X485286Y13817D01*
X485417Y13840D01*
X485570Y13864D01*
X485724Y13911D01*
X485890Y13971D01*
X486044Y14053D01*
X486068Y14065D01*
X486115Y14101D01*
X486186Y14160D01*
X486281Y14231D01*
X486387Y14326D01*
X486506Y14444D01*
X486612Y14574D01*
X486719Y14716D01*
X486730Y14740D01*
X486766Y14787D01*
X486813Y14882D01*
X486872Y15012D01*
X486944Y15166D01*
X487015Y15355D01*
X487085Y15580D01*
X487157Y15829D01*
Y15841D01*
X487168Y15864D01*
Y15900D01*
X487180Y15947D01*
X487204Y16018D01*
X487216Y16089D01*
X487251Y16279D01*
X487275Y16492D01*
X487310Y16740D01*
X487322Y17001D01*
X487334Y17273D01*
Y17285D01*
Y17332D01*
Y17403D01*
Y17498D01*
X487322Y17486D01*
X487275Y17415D01*
X487192Y17320D01*
X487085Y17190D01*
X486944Y17048D01*
X486778Y16894D01*
X486577Y16740D01*
X486363Y16598D01*
X486352D01*
X486340Y16586D01*
X486304Y16563D01*
X486257Y16551D01*
X486127Y16492D01*
X485973Y16433D01*
X485772Y16362D01*
X485547Y16314D01*
X485298Y16267D01*
X485038Y16255D01*
X484991D01*
X484920Y16267D01*
X484837D01*
X484730Y16279D01*
X484612Y16302D01*
X484482Y16326D01*
X484339Y16362D01*
X484186Y16409D01*
X484020Y16468D01*
X483854Y16527D01*
X483677Y16610D01*
X483511Y16717D01*
X483333Y16823D01*
X483168Y16953D01*
X483014Y17107D01*
X483002Y17119D01*
X482978Y17143D01*
X482943Y17202D01*
X482884Y17261D01*
X482824Y17356D01*
X482753Y17450D01*
X482682Y17581D01*
X482611Y17723D01*
X482528Y17877D01*
X482458Y18042D01*
X482387Y18232D01*
X482327Y18433D01*
X482268Y18658D01*
X482233Y18883D01*
X482209Y19131D01*
X482197Y19392D01*
Y19404D01*
Y19451D01*
X482209Y19534D01*
Y19628D01*
X482221Y19759D01*
X482244Y19901D01*
X482268Y20055D01*
X482304Y20232D01*
X482351Y20410D01*
X482410Y20599D01*
X482469Y20800D01*
X482552Y20990D01*
X482659Y21191D01*
X482765Y21380D01*
X482896Y21558D01*
X483049Y21735D01*
X483061Y21747D01*
X483085Y21771D01*
X483132Y21818D01*
X483203Y21877D01*
X483286Y21948D01*
X483393Y22019D01*
X483511Y22102D01*
X483641Y22185D01*
X483795Y22268D01*
X483961Y22351D01*
X484138Y22422D01*
X484328Y22493D01*
X484529Y22552D01*
X484742Y22599D01*
X484967Y22623D01*
X485204Y22635D01*
X485298D01*
X485357Y22623D01*
D02*
G37*
G36*
X577480Y13000D02*
X576297D01*
Y20504D01*
X576273Y20492D01*
X576214Y20433D01*
X576131Y20350D01*
X576001Y20256D01*
X575835Y20126D01*
X575645Y19995D01*
X575421Y19842D01*
X575172Y19688D01*
X575160D01*
X575136Y19676D01*
X575101Y19652D01*
X575054Y19617D01*
X574924Y19546D01*
X574758Y19463D01*
X574568Y19368D01*
X574367Y19261D01*
X574154Y19167D01*
X573941Y19084D01*
Y20220D01*
X573953D01*
X573988Y20244D01*
X574036Y20268D01*
X574107Y20303D01*
X574190Y20350D01*
X574296Y20398D01*
X574403Y20469D01*
X574521Y20540D01*
X574793Y20694D01*
X575077Y20895D01*
X575373Y21108D01*
X575657Y21345D01*
X575669Y21356D01*
X575693Y21380D01*
X575728Y21416D01*
X575776Y21463D01*
X575906Y21593D01*
X576072Y21759D01*
X576237Y21948D01*
X576415Y22173D01*
X576581Y22398D01*
X576711Y22635D01*
X577480D01*
Y13000D01*
D02*
G37*
G36*
X558873Y21463D02*
X553215D01*
Y18540D01*
X558518D01*
Y17403D01*
X553215D01*
Y14136D01*
X559098D01*
Y13000D01*
X551949D01*
Y22599D01*
X558873D01*
Y21463D01*
D02*
G37*
G36*
X545676Y14136D02*
X550410D01*
Y13000D01*
X544409D01*
Y22599D01*
X545676D01*
Y14136D01*
D02*
G37*
G36*
X528809Y22587D02*
X529057D01*
X529330Y22564D01*
X529614Y22540D01*
X529886Y22505D01*
X530016Y22481D01*
X530135Y22457D01*
X530146D01*
X530170Y22445D01*
X530217Y22434D01*
X530277Y22422D01*
X530348Y22398D01*
X530430Y22374D01*
X530620Y22303D01*
X530833Y22209D01*
X531070Y22090D01*
X531318Y21948D01*
X531543Y21771D01*
X531555Y21759D01*
X531579Y21747D01*
X531614Y21700D01*
X531673Y21652D01*
X531732Y21593D01*
X531804Y21510D01*
X531886Y21428D01*
X531969Y21321D01*
X532159Y21084D01*
X532348Y20812D01*
X532525Y20481D01*
X532679Y20126D01*
Y20114D01*
X532691Y20078D01*
X532715Y20031D01*
X532738Y19948D01*
X532762Y19853D01*
X532798Y19747D01*
X532833Y19617D01*
X532869Y19463D01*
X532904Y19309D01*
X532940Y19131D01*
X532975Y18942D01*
X532999Y18741D01*
X533046Y18315D01*
X533058Y17841D01*
Y17829D01*
Y17794D01*
Y17735D01*
Y17664D01*
X533046Y17557D01*
Y17450D01*
X533034Y17332D01*
X533023Y17190D01*
X532999Y16894D01*
X532952Y16563D01*
X532881Y16231D01*
X532798Y15900D01*
Y15888D01*
X532786Y15864D01*
X532774Y15817D01*
X532750Y15758D01*
X532727Y15687D01*
X532691Y15604D01*
X532620Y15415D01*
X532525Y15190D01*
X532407Y14953D01*
X532277Y14728D01*
X532135Y14503D01*
X532123Y14480D01*
X532064Y14409D01*
X531981Y14314D01*
X531886Y14195D01*
X531756Y14053D01*
X531602Y13911D01*
X531448Y13769D01*
X531271Y13639D01*
X531247Y13627D01*
X531188Y13592D01*
X531081Y13533D01*
X530951Y13462D01*
X530785Y13379D01*
X530584Y13296D01*
X530371Y13225D01*
X530123Y13154D01*
X530111D01*
X530087Y13142D01*
X530052D01*
X530004Y13130D01*
X529945Y13118D01*
X529862Y13107D01*
X529673Y13083D01*
X529448Y13047D01*
X529188Y13024D01*
X528892Y13012D01*
X528572Y13000D01*
X525116D01*
Y22599D01*
X528702D01*
X528809Y22587D01*
D02*
G37*
G36*
X454642Y21463D02*
X448984D01*
Y18539D01*
X454287D01*
Y17403D01*
X448984D01*
Y14136D01*
X454867D01*
Y13000D01*
X447718D01*
Y22599D01*
X454642D01*
Y21463D01*
D02*
G37*
G36*
X519127Y22753D02*
X519245Y22741D01*
X519375Y22729D01*
X519529Y22718D01*
X519695Y22682D01*
X519872Y22647D01*
X520074Y22611D01*
X520476Y22493D01*
X520677Y22422D01*
X520890Y22339D01*
X521091Y22244D01*
X521293Y22126D01*
X521305Y22114D01*
X521340Y22102D01*
X521399Y22055D01*
X521470Y22008D01*
X521553Y21948D01*
X521660Y21865D01*
X521778Y21771D01*
X521896Y21664D01*
X522027Y21546D01*
X522157Y21416D01*
X522287Y21262D01*
X522429Y21108D01*
X522559Y20942D01*
X522689Y20753D01*
X522808Y20563D01*
X522914Y20350D01*
X522926Y20339D01*
X522938Y20303D01*
X522962Y20232D01*
X523009Y20149D01*
X523045Y20043D01*
X523092Y19913D01*
X523151Y19770D01*
X523198Y19605D01*
X523258Y19427D01*
X523305Y19226D01*
X523352Y19013D01*
X523400Y18788D01*
X523435Y18551D01*
X523459Y18303D01*
X523471Y18042D01*
X523483Y17782D01*
Y17770D01*
Y17723D01*
Y17640D01*
X523471Y17533D01*
Y17403D01*
X523447Y17261D01*
X523435Y17084D01*
X523411Y16906D01*
X523376Y16705D01*
X523340Y16504D01*
X523234Y16054D01*
X523163Y15829D01*
X523092Y15604D01*
X522997Y15379D01*
X522891Y15166D01*
X522879Y15154D01*
X522867Y15119D01*
X522831Y15060D01*
X522784Y14977D01*
X522725Y14882D01*
X522642Y14776D01*
X522559Y14645D01*
X522464Y14515D01*
X522346Y14385D01*
X522228Y14243D01*
X522086Y14089D01*
X521932Y13947D01*
X521778Y13805D01*
X521600Y13675D01*
X521423Y13544D01*
X521222Y13426D01*
X521210Y13414D01*
X521174Y13403D01*
X521115Y13367D01*
X521032Y13331D01*
X520938Y13284D01*
X520819Y13237D01*
X520677Y13189D01*
X520523Y13130D01*
X520358Y13071D01*
X520180Y13024D01*
X519991Y12976D01*
X519790Y12929D01*
X519352Y12858D01*
X519127Y12846D01*
X518890Y12834D01*
X518760D01*
X518665Y12846D01*
X518547Y12858D01*
X518405Y12870D01*
X518251Y12894D01*
X518085Y12917D01*
X517896Y12953D01*
X517706Y12988D01*
X517292Y13107D01*
X517091Y13189D01*
X516878Y13272D01*
X516665Y13367D01*
X516464Y13485D01*
X516452Y13497D01*
X516416Y13521D01*
X516357Y13556D01*
X516286Y13604D01*
X516203Y13675D01*
X516097Y13746D01*
X515990Y13840D01*
X515860Y13947D01*
X515730Y14077D01*
X515599Y14207D01*
X515469Y14349D01*
X515339Y14515D01*
X515209Y14681D01*
X515079Y14858D01*
X514960Y15060D01*
X514854Y15261D01*
Y15273D01*
X514830Y15308D01*
X514806Y15379D01*
X514771Y15462D01*
X514724Y15568D01*
X514676Y15687D01*
X514629Y15829D01*
X514581Y15983D01*
X514534Y16160D01*
X514487Y16350D01*
X514440Y16551D01*
X514392Y16752D01*
X514333Y17202D01*
X514321Y17427D01*
X514309Y17664D01*
Y17675D01*
Y17687D01*
Y17723D01*
Y17770D01*
X514321Y17888D01*
X514333Y18054D01*
X514345Y18255D01*
X514380Y18492D01*
X514416Y18752D01*
X514475Y19025D01*
X514534Y19321D01*
X514617Y19628D01*
X514724Y19936D01*
X514854Y20256D01*
X514996Y20563D01*
X515162Y20859D01*
X515363Y21144D01*
X515588Y21404D01*
X515599Y21416D01*
X515647Y21463D01*
X515718Y21534D01*
X515824Y21617D01*
X515943Y21723D01*
X516097Y21830D01*
X516274Y21960D01*
X516487Y22090D01*
X516712Y22209D01*
X516961Y22339D01*
X517233Y22445D01*
X517529Y22552D01*
X517836Y22635D01*
X518180Y22706D01*
X518535Y22753D01*
X518902Y22765D01*
X519032D01*
X519127Y22753D01*
D02*
G37*
G36*
X461057Y22753D02*
X461176Y22741D01*
X461306Y22729D01*
X461460Y22718D01*
X461625Y22682D01*
X461803Y22647D01*
X462004Y22611D01*
X462407Y22493D01*
X462608Y22422D01*
X462821Y22339D01*
X463022Y22244D01*
X463223Y22126D01*
X463235Y22114D01*
X463271Y22102D01*
X463330Y22055D01*
X463401Y22008D01*
X463484Y21948D01*
X463590Y21865D01*
X463709Y21771D01*
X463827Y21664D01*
X463957Y21546D01*
X464087Y21416D01*
X464218Y21262D01*
X464360Y21108D01*
X464490Y20942D01*
X464620Y20753D01*
X464738Y20563D01*
X464845Y20350D01*
X464857Y20339D01*
X464869Y20303D01*
X464892Y20232D01*
X464940Y20149D01*
X464975Y20043D01*
X465023Y19913D01*
X465082Y19770D01*
X465129Y19605D01*
X465188Y19427D01*
X465235Y19226D01*
X465283Y19013D01*
X465330Y18788D01*
X465366Y18551D01*
X465389Y18303D01*
X465401Y18042D01*
X465413Y17782D01*
Y17770D01*
Y17723D01*
Y17640D01*
X465401Y17533D01*
Y17403D01*
X465378Y17261D01*
X465366Y17084D01*
X465342Y16906D01*
X465307Y16705D01*
X465271Y16504D01*
X465164Y16054D01*
X465093Y15829D01*
X465023Y15604D01*
X464928Y15379D01*
X464821Y15166D01*
X464809Y15154D01*
X464798Y15119D01*
X464762Y15059D01*
X464715Y14977D01*
X464656Y14882D01*
X464573Y14776D01*
X464490Y14645D01*
X464395Y14515D01*
X464277Y14385D01*
X464158Y14243D01*
X464016Y14089D01*
X463862Y13947D01*
X463709Y13805D01*
X463531Y13675D01*
X463354Y13544D01*
X463152Y13426D01*
X463140Y13414D01*
X463105Y13402D01*
X463046Y13367D01*
X462963Y13331D01*
X462868Y13284D01*
X462750Y13237D01*
X462608Y13189D01*
X462454Y13130D01*
X462288Y13071D01*
X462111Y13024D01*
X461921Y12976D01*
X461720Y12929D01*
X461282Y12858D01*
X461057Y12846D01*
X460821Y12834D01*
X460690D01*
X460596Y12846D01*
X460477Y12858D01*
X460335Y12870D01*
X460181Y12894D01*
X460016Y12917D01*
X459826Y12953D01*
X459637Y12988D01*
X459223Y13106D01*
X459021Y13189D01*
X458808Y13272D01*
X458595Y13367D01*
X458394Y13485D01*
X458382Y13497D01*
X458347Y13521D01*
X458288Y13556D01*
X458217Y13604D01*
X458134Y13675D01*
X458027Y13746D01*
X457921Y13840D01*
X457790Y13947D01*
X457660Y14077D01*
X457530Y14207D01*
X457400Y14349D01*
X457270Y14515D01*
X457139Y14681D01*
X457009Y14858D01*
X456891Y15059D01*
X456784Y15261D01*
Y15273D01*
X456761Y15308D01*
X456737Y15379D01*
X456702Y15462D01*
X456654Y15568D01*
X456607Y15687D01*
X456559Y15829D01*
X456512Y15983D01*
X456465Y16160D01*
X456417Y16350D01*
X456370Y16551D01*
X456323Y16752D01*
X456264Y17202D01*
X456252Y17427D01*
X456240Y17664D01*
Y17675D01*
Y17687D01*
Y17723D01*
Y17770D01*
X456252Y17888D01*
X456264Y18054D01*
X456275Y18255D01*
X456311Y18492D01*
X456346Y18752D01*
X456406Y19025D01*
X456465Y19321D01*
X456548Y19628D01*
X456654Y19936D01*
X456784Y20256D01*
X456926Y20563D01*
X457092Y20859D01*
X457293Y21143D01*
X457518Y21404D01*
X457530Y21416D01*
X457577Y21463D01*
X457648Y21534D01*
X457755Y21617D01*
X457873Y21723D01*
X458027Y21830D01*
X458205Y21960D01*
X458418Y22090D01*
X458643Y22209D01*
X458891Y22339D01*
X459164Y22445D01*
X459459Y22552D01*
X459767Y22635D01*
X460110Y22706D01*
X460466Y22753D01*
X460832Y22765D01*
X460963D01*
X461057Y22753D01*
D02*
G37*
%LPC*%
G36*
X485346Y21664D02*
X485275D01*
X485215Y21652D01*
X485144Y21641D01*
X485061Y21629D01*
X484872Y21581D01*
X484659Y21510D01*
X484434Y21392D01*
X484316Y21321D01*
X484198Y21226D01*
X484079Y21132D01*
X483973Y21013D01*
X483961Y21001D01*
X483949Y20990D01*
X483925Y20942D01*
X483890Y20895D01*
X483842Y20836D01*
X483795Y20753D01*
X483748Y20670D01*
X483689Y20563D01*
X483641Y20457D01*
X483582Y20327D01*
X483499Y20043D01*
X483428Y19723D01*
X483416Y19546D01*
X483404Y19356D01*
Y19344D01*
Y19321D01*
Y19273D01*
X483416Y19202D01*
Y19119D01*
X483428Y19037D01*
X483475Y18823D01*
X483535Y18587D01*
X483629Y18338D01*
X483771Y18090D01*
X483854Y17971D01*
X483949Y17865D01*
X483961Y17853D01*
X483973Y17841D01*
X484008Y17817D01*
X484044Y17782D01*
X484162Y17687D01*
X484328Y17581D01*
X484517Y17474D01*
X484754Y17391D01*
X485014Y17320D01*
X485156Y17308D01*
X485310Y17297D01*
X485393D01*
X485452Y17308D01*
X485523D01*
X485606Y17332D01*
X485795Y17368D01*
X486008Y17439D01*
X486233Y17533D01*
X486458Y17675D01*
X486565Y17770D01*
X486659Y17865D01*
X486671Y17877D01*
X486683Y17888D01*
X486707Y17924D01*
X486742Y17971D01*
X486778Y18031D01*
X486825Y18102D01*
X486872Y18184D01*
X486932Y18279D01*
X486979Y18386D01*
X487026Y18504D01*
X487109Y18776D01*
X487168Y19096D01*
X487192Y19261D01*
Y19451D01*
Y19463D01*
Y19498D01*
Y19546D01*
X487180Y19617D01*
Y19711D01*
X487168Y19806D01*
X487121Y20031D01*
X487062Y20291D01*
X486967Y20563D01*
X486825Y20824D01*
X486742Y20942D01*
X486648Y21061D01*
Y21072D01*
X486624Y21084D01*
X486553Y21155D01*
X486435Y21250D01*
X486281Y21368D01*
X486091Y21475D01*
X485878Y21570D01*
X485618Y21641D01*
X485488Y21652D01*
X485346Y21664D01*
D02*
G37*
G36*
X528596Y21463D02*
X526382D01*
Y14136D01*
X528667D01*
X528761Y14148D01*
X528975Y14160D01*
X529211Y14172D01*
X529460Y14207D01*
X529697Y14243D01*
X529921Y14302D01*
X529933D01*
X529945Y14314D01*
X530016Y14338D01*
X530111Y14373D01*
X530229Y14432D01*
X530371Y14503D01*
X530513Y14586D01*
X530655Y14681D01*
X530785Y14799D01*
X530809Y14823D01*
X530857Y14882D01*
X530939Y14988D01*
X531046Y15131D01*
X531152Y15296D01*
X531271Y15509D01*
X531377Y15746D01*
X531484Y16018D01*
Y16030D01*
X531496Y16054D01*
X531507Y16101D01*
X531519Y16149D01*
X531543Y16231D01*
X531567Y16314D01*
X531590Y16421D01*
X531614Y16539D01*
X531638Y16658D01*
X531661Y16799D01*
X531709Y17119D01*
X531732Y17474D01*
X531744Y17865D01*
Y17877D01*
Y17936D01*
Y18007D01*
X531732Y18113D01*
Y18244D01*
X531721Y18386D01*
X531709Y18540D01*
X531685Y18717D01*
X531626Y19084D01*
X531531Y19475D01*
X531413Y19842D01*
X531330Y20019D01*
X531247Y20173D01*
Y20185D01*
X531223Y20208D01*
X531200Y20256D01*
X531164Y20303D01*
X531058Y20445D01*
X530916Y20611D01*
X530738Y20800D01*
X530525Y20978D01*
X530300Y21132D01*
X530170Y21203D01*
X530040Y21262D01*
X530016Y21274D01*
X529981Y21286D01*
X529945Y21297D01*
X529886Y21309D01*
X529815Y21321D01*
X529744Y21345D01*
X529649Y21368D01*
X529531Y21380D01*
X529412Y21404D01*
X529282Y21416D01*
X529128Y21428D01*
X528975Y21439D01*
X528797Y21451D01*
X528596Y21463D01*
D02*
G37*
G36*
X518902Y21676D02*
X518772D01*
X518677Y21664D01*
X518559Y21652D01*
X518428Y21629D01*
X518274Y21593D01*
X518109Y21558D01*
X517931Y21510D01*
X517742Y21451D01*
X517552Y21368D01*
X517351Y21286D01*
X517162Y21179D01*
X516961Y21049D01*
X516771Y20907D01*
X516582Y20741D01*
X516570Y20729D01*
X516546Y20694D01*
X516499Y20646D01*
X516428Y20563D01*
X516357Y20457D01*
X516274Y20339D01*
X516191Y20185D01*
X516108Y20007D01*
X516014Y19806D01*
X515931Y19581D01*
X515848Y19332D01*
X515777Y19048D01*
X515718Y18741D01*
X515670Y18409D01*
X515635Y18042D01*
X515623Y17652D01*
Y17628D01*
Y17581D01*
X515635Y17486D01*
Y17368D01*
X515647Y17214D01*
X515670Y17048D01*
X515706Y16859D01*
X515742Y16658D01*
X515789Y16444D01*
X515848Y16220D01*
X515919Y15995D01*
X516014Y15770D01*
X516120Y15545D01*
X516239Y15320D01*
X516381Y15107D01*
X516546Y14918D01*
X516558Y14906D01*
X516594Y14870D01*
X516641Y14823D01*
X516712Y14764D01*
X516807Y14693D01*
X516913Y14598D01*
X517043Y14515D01*
X517186Y14420D01*
X517351Y14326D01*
X517529Y14243D01*
X517718Y14160D01*
X517919Y14077D01*
X518144Y14018D01*
X518381Y13971D01*
X518618Y13935D01*
X518878Y13923D01*
X518937D01*
X519020Y13935D01*
X519115D01*
X519233Y13959D01*
X519375Y13982D01*
X519541Y14006D01*
X519707Y14053D01*
X519896Y14101D01*
X520085Y14172D01*
X520275Y14255D01*
X520476Y14349D01*
X520677Y14468D01*
X520867Y14598D01*
X521056Y14752D01*
X521234Y14929D01*
X521245Y14941D01*
X521269Y14977D01*
X521316Y15036D01*
X521376Y15119D01*
X521447Y15225D01*
X521530Y15344D01*
X521612Y15497D01*
X521707Y15663D01*
X521790Y15853D01*
X521873Y16066D01*
X521956Y16302D01*
X522027Y16563D01*
X522086Y16835D01*
X522133Y17131D01*
X522157Y17450D01*
X522169Y17782D01*
Y17794D01*
Y17829D01*
Y17900D01*
Y17983D01*
X522157Y18078D01*
X522145Y18196D01*
X522133Y18326D01*
X522121Y18480D01*
X522074Y18800D01*
X522003Y19143D01*
X521896Y19486D01*
X521766Y19830D01*
Y19842D01*
X521743Y19865D01*
X521731Y19913D01*
X521695Y19972D01*
X521648Y20043D01*
X521600Y20137D01*
X521470Y20327D01*
X521316Y20552D01*
X521115Y20777D01*
X520878Y20990D01*
X520606Y21191D01*
X520594D01*
X520571Y21214D01*
X520535Y21238D01*
X520476Y21262D01*
X520405Y21309D01*
X520322Y21345D01*
X520216Y21392D01*
X520109Y21439D01*
X519860Y21522D01*
X519565Y21605D01*
X519245Y21652D01*
X518902Y21676D01*
D02*
G37*
G36*
X460832Y21676D02*
X460702D01*
X460607Y21664D01*
X460489Y21652D01*
X460359Y21629D01*
X460205Y21593D01*
X460039Y21558D01*
X459862Y21510D01*
X459672Y21451D01*
X459483Y21368D01*
X459282Y21286D01*
X459092Y21179D01*
X458891Y21049D01*
X458702Y20907D01*
X458512Y20741D01*
X458501Y20729D01*
X458477Y20694D01*
X458430Y20646D01*
X458359Y20563D01*
X458288Y20457D01*
X458205Y20339D01*
X458122Y20185D01*
X458039Y20007D01*
X457944Y19806D01*
X457862Y19581D01*
X457779Y19332D01*
X457708Y19048D01*
X457648Y18741D01*
X457601Y18409D01*
X457566Y18042D01*
X457554Y17652D01*
Y17628D01*
Y17581D01*
X457566Y17486D01*
Y17368D01*
X457577Y17214D01*
X457601Y17048D01*
X457637Y16859D01*
X457672Y16657D01*
X457719Y16444D01*
X457779Y16220D01*
X457850Y15995D01*
X457944Y15770D01*
X458051Y15545D01*
X458169Y15320D01*
X458311Y15107D01*
X458477Y14918D01*
X458489Y14906D01*
X458524Y14870D01*
X458572Y14823D01*
X458643Y14764D01*
X458737Y14693D01*
X458844Y14598D01*
X458974Y14515D01*
X459116Y14420D01*
X459282Y14326D01*
X459459Y14243D01*
X459649Y14160D01*
X459850Y14077D01*
X460075Y14018D01*
X460312Y13971D01*
X460548Y13935D01*
X460809Y13923D01*
X460868D01*
X460951Y13935D01*
X461045D01*
X461164Y13959D01*
X461306Y13982D01*
X461472Y14006D01*
X461637Y14053D01*
X461827Y14101D01*
X462016Y14172D01*
X462205Y14255D01*
X462407Y14349D01*
X462608Y14468D01*
X462797Y14598D01*
X462987Y14752D01*
X463164Y14929D01*
X463176Y14941D01*
X463200Y14977D01*
X463247Y15036D01*
X463306Y15119D01*
X463377Y15225D01*
X463460Y15344D01*
X463543Y15497D01*
X463638Y15663D01*
X463721Y15853D01*
X463803Y16066D01*
X463886Y16302D01*
X463957Y16563D01*
X464016Y16835D01*
X464064Y17131D01*
X464087Y17450D01*
X464099Y17782D01*
Y17794D01*
Y17829D01*
Y17900D01*
Y17983D01*
X464087Y18078D01*
X464076Y18196D01*
X464064Y18326D01*
X464052Y18480D01*
X464005Y18800D01*
X463933Y19143D01*
X463827Y19486D01*
X463697Y19830D01*
Y19841D01*
X463673Y19865D01*
X463661Y19913D01*
X463626Y19972D01*
X463578Y20043D01*
X463531Y20137D01*
X463401Y20327D01*
X463247Y20552D01*
X463046Y20777D01*
X462809Y20990D01*
X462537Y21191D01*
X462525D01*
X462501Y21214D01*
X462466Y21238D01*
X462407Y21262D01*
X462336Y21309D01*
X462253Y21345D01*
X462146Y21392D01*
X462040Y21439D01*
X461791Y21522D01*
X461495Y21605D01*
X461176Y21652D01*
X460832Y21676D01*
D02*
G37*
%LPD*%
D10*
X137002Y112220D02*
G03*
X137002Y112220I-762J0D01*
G01*
X103142Y153930D02*
Y179837D01*
X116858D01*
Y153930D02*
Y179837D01*
X103142Y153930D02*
X116858D01*
X109906Y98666D02*
Y109334D01*
X90094Y98666D02*
X109906D01*
X90094D02*
Y109334D01*
X109906D01*
X504142Y118716D02*
X516842D01*
Y90776D02*
Y118716D01*
X504142Y90776D02*
X516842D01*
X504142D02*
Y118716D01*
X112742Y185664D02*
Y202428D01*
X103090D02*
X112742D01*
X103090Y185664D02*
Y202428D01*
Y185664D02*
X112742D01*
X226750Y83245D02*
X387250D01*
X226750Y226755D02*
X387250D01*
X226750Y83245D02*
Y226755D01*
X387250Y83245D02*
Y226755D01*
X650976Y75550D02*
Y150480D01*
X570440Y75550D02*
Y150480D01*
Y75550D02*
X650976D01*
X570440Y150480D02*
X650976D01*
X19900Y236000D02*
X95900D01*
X19900Y160000D02*
X95900D01*
Y236000D01*
X19900Y160000D02*
Y236000D01*
X123094Y179209D02*
X142906D01*
X123094Y169557D02*
Y179209D01*
X142906Y169557D02*
Y179209D01*
X123094Y169557D02*
X142906D01*
X356826Y57094D02*
Y76906D01*
X347174D02*
X356826D01*
X347174Y57094D02*
X356826D01*
X347174D02*
Y76906D01*
X372383Y57094D02*
Y76906D01*
X362731D02*
X372383D01*
X362731Y57094D02*
X372383D01*
X362731D02*
Y76906D01*
X387816Y57094D02*
Y76906D01*
X378164D02*
X387816D01*
X378164Y57094D02*
X387816D01*
X378164D02*
Y76906D01*
X243183Y234094D02*
Y253906D01*
Y234094D02*
X252834D01*
X243183Y253906D02*
X252834D01*
Y234094D02*
Y253906D01*
X435142Y118716D02*
X447842D01*
Y90776D02*
Y118716D01*
X435142Y90776D02*
X447842D01*
X435142D02*
Y118716D01*
X287666Y233094D02*
X298334D01*
X287666D02*
Y252906D01*
X298334D01*
Y233094D02*
Y252906D01*
X453666Y99094D02*
X464334D01*
X453666D02*
Y118906D01*
X464334D01*
Y99094D02*
Y118906D01*
X522666Y99094D02*
X533334D01*
X522666D02*
Y118906D01*
X533334D01*
Y99094D02*
Y118906D01*
X579725Y204906D02*
X590393D01*
Y185094D02*
Y204906D01*
X579725Y185094D02*
X590393D01*
X579725D02*
Y204906D01*
X605277D02*
X615945D01*
Y185094D02*
Y204906D01*
X605277Y185094D02*
X615945D01*
X605277D02*
Y204906D01*
X396906Y248666D02*
Y259334D01*
X377094Y248666D02*
X396906D01*
X377094D02*
Y259334D01*
X396906D01*
X121094Y98666D02*
Y109334D01*
X140906D01*
Y98666D02*
Y109334D01*
X121094Y98666D02*
X140906D01*
X235906Y66666D02*
Y77334D01*
X216094Y66666D02*
X235906D01*
X216094D02*
Y77334D01*
X235906D01*
X102000Y115884D02*
Y120116D01*
X100942Y121174D01*
X98826D01*
X97768Y120116D01*
Y115884D01*
X98826Y114826D01*
X100942D01*
X99884Y116942D02*
X102000Y114826D01*
X100942D02*
X102000Y115884D01*
X104116Y114826D02*
X106232D01*
X105174D01*
Y121174D01*
X104116Y120116D01*
X151942Y175499D02*
X150884Y176558D01*
X148768D01*
X147710Y175499D01*
Y171268D01*
X148768Y170210D01*
X150884D01*
X151942Y171268D01*
X158290Y176558D02*
X154058D01*
Y173384D01*
X156174Y174442D01*
X157232D01*
X158290Y173384D01*
Y171268D01*
X157232Y170210D01*
X155116D01*
X154058Y171268D01*
X213768Y91174D02*
Y85884D01*
X214826Y84826D01*
X216942D01*
X218000Y85884D01*
Y91174D01*
X220116Y84826D02*
X222232D01*
X221174D01*
Y91174D01*
X220116Y90116D01*
X619949Y219174D02*
X624181D01*
X622065D01*
Y212826D01*
X626297D02*
Y219174D01*
X629471D01*
X630529Y218116D01*
Y216000D01*
X629471Y214942D01*
X626297D01*
X632645Y212826D02*
X634761D01*
X633703D01*
Y219174D01*
X632645Y218116D01*
X637935Y212826D02*
X640051D01*
X638993D01*
Y219174D01*
X637935Y218116D01*
X549891Y219174D02*
X554123D01*
X552007D01*
Y212826D01*
X556239D02*
Y219174D01*
X559413D01*
X560471Y218116D01*
Y216000D01*
X559413Y214942D01*
X556239D01*
X562587Y212826D02*
X564703D01*
X563645D01*
Y219174D01*
X562587Y218116D01*
X567877D02*
X568935Y219174D01*
X571051D01*
X572109Y218116D01*
Y213884D01*
X571051Y212826D01*
X568935D01*
X567877Y213884D01*
Y218116D01*
X325174Y62464D02*
Y58232D01*
Y60348D01*
X318826D01*
Y56116D02*
X325174D01*
Y52942D01*
X324116Y51884D01*
X322000D01*
X320942Y52942D01*
Y56116D01*
X319884Y49768D02*
X318826Y48710D01*
Y46594D01*
X319884Y45536D01*
X324116D01*
X325174Y46594D01*
Y48710D01*
X324116Y49768D01*
X323058D01*
X322000Y48710D01*
Y45536D01*
X308174Y62464D02*
Y58232D01*
Y60348D01*
X301826D01*
Y56116D02*
X308174D01*
Y52942D01*
X307116Y51884D01*
X305000D01*
X303942Y52942D01*
Y56116D01*
X307116Y49768D02*
X308174Y48710D01*
Y46594D01*
X307116Y45536D01*
X306058D01*
X305000Y46594D01*
X303942Y45536D01*
X302884D01*
X301826Y46594D01*
Y48710D01*
X302884Y49768D01*
X303942D01*
X305000Y48710D01*
X306058Y49768D01*
X307116D01*
X305000Y48710D02*
Y46594D01*
X391536Y241174D02*
X395768D01*
X393652D01*
Y234826D01*
X397884D02*
Y241174D01*
X401058D01*
X402116Y240116D01*
Y238000D01*
X401058Y236942D01*
X397884D01*
X404232Y241174D02*
X408464D01*
Y240116D01*
X404232Y235884D01*
Y234826D01*
X251174Y62464D02*
Y58232D01*
Y60348D01*
X244826D01*
Y56116D02*
X251174D01*
Y52942D01*
X250116Y51884D01*
X248000D01*
X246942Y52942D01*
Y56116D01*
X251174Y45536D02*
X250116Y47652D01*
X248000Y49768D01*
X245884D01*
X244826Y48710D01*
Y46594D01*
X245884Y45536D01*
X246942D01*
X248000Y46594D01*
Y49768D01*
X340826Y244536D02*
Y248768D01*
Y246652D01*
X347174D01*
Y250884D02*
X340826D01*
Y254058D01*
X341884Y255116D01*
X344000D01*
X345058Y254058D01*
Y250884D01*
X340826Y261464D02*
Y257232D01*
X344000D01*
X342942Y259348D01*
Y260406D01*
X344000Y261464D01*
X346116D01*
X347174Y260406D01*
Y258290D01*
X346116Y257232D01*
X308826Y259536D02*
Y263768D01*
Y261652D01*
X315174D01*
Y265884D02*
X308826D01*
Y269058D01*
X309884Y270116D01*
X312000D01*
X313058Y269058D01*
Y265884D01*
X315174Y275406D02*
X308826D01*
X312000Y272232D01*
Y276464D01*
X318826Y243536D02*
Y247768D01*
Y245652D01*
X325174D01*
Y249884D02*
X318826D01*
Y253058D01*
X319884Y254116D01*
X322000D01*
X323058Y253058D01*
Y249884D01*
X319884Y256232D02*
X318826Y257290D01*
Y259406D01*
X319884Y260464D01*
X320942D01*
X322000Y259406D01*
Y258348D01*
Y259406D01*
X323058Y260464D01*
X324116D01*
X325174Y259406D01*
Y257290D01*
X324116Y256232D01*
X330826Y259536D02*
Y263768D01*
Y261652D01*
X337174D01*
Y265884D02*
X330826D01*
Y269058D01*
X331884Y270116D01*
X334000D01*
X335058Y269058D01*
Y265884D01*
X337174Y276464D02*
Y272232D01*
X332942Y276464D01*
X331884D01*
X330826Y275406D01*
Y273290D01*
X331884Y272232D01*
X362826Y247594D02*
Y251826D01*
Y249710D01*
X369174D01*
Y253942D02*
X362826D01*
Y257116D01*
X363884Y258174D01*
X366000D01*
X367058Y257116D01*
Y253942D01*
X369174Y260290D02*
Y262406D01*
Y261348D01*
X362826D01*
X363884Y260290D01*
X399065Y249826D02*
Y256174D01*
X402239D01*
X403297Y255116D01*
Y253000D01*
X402239Y251942D01*
X399065D01*
X401181D02*
X403297Y249826D01*
X405413D02*
X407529D01*
X406471D01*
Y256174D01*
X405413Y255116D01*
X410703D02*
X411761Y256174D01*
X413877D01*
X414935Y255116D01*
Y250884D01*
X413877Y249826D01*
X411761D01*
X410703Y250884D01*
Y255116D01*
X604710Y175826D02*
Y182174D01*
X607884D01*
X608942Y181116D01*
Y179000D01*
X607884Y177942D01*
X604710D01*
X606826D02*
X608942Y175826D01*
X611058Y181116D02*
X612116Y182174D01*
X614232D01*
X615290Y181116D01*
Y180058D01*
X614232Y179000D01*
X615290Y177942D01*
Y176884D01*
X614232Y175826D01*
X612116D01*
X611058Y176884D01*
Y177942D01*
X612116Y179000D01*
X611058Y180058D01*
Y181116D01*
X612116Y179000D02*
X614232D01*
X579710Y175826D02*
Y182174D01*
X582884D01*
X583942Y181116D01*
Y179000D01*
X582884Y177942D01*
X579710D01*
X581826D02*
X583942Y175826D01*
X590290Y182174D02*
X586058D01*
Y179000D01*
X588174Y180058D01*
X589232D01*
X590290Y179000D01*
Y176884D01*
X589232Y175826D01*
X587116D01*
X586058Y176884D01*
X121710Y154826D02*
Y161174D01*
X124884D01*
X125942Y160116D01*
Y158000D01*
X124884Y156942D01*
X121710D01*
X123826D02*
X125942Y154826D01*
X131232D02*
Y161174D01*
X128058Y158000D01*
X132290D01*
X532174Y124710D02*
X525826D01*
Y127884D01*
X526884Y128942D01*
X529000D01*
X530058Y127884D01*
Y124710D01*
Y126826D02*
X532174Y128942D01*
X526884Y131058D02*
X525826Y132116D01*
Y134232D01*
X526884Y135290D01*
X527942D01*
X529000Y134232D01*
Y133174D01*
Y134232D01*
X530058Y135290D01*
X531116D01*
X532174Y134232D01*
Y132116D01*
X531116Y131058D01*
X462174Y126710D02*
X455826D01*
Y129884D01*
X456884Y130942D01*
X459000D01*
X460058Y129884D01*
Y126710D01*
Y128826D02*
X462174Y130942D01*
Y137290D02*
Y133058D01*
X457942Y137290D01*
X456884D01*
X455826Y136232D01*
Y134116D01*
X456884Y133058D01*
X296173Y257768D02*
X289825D01*
Y260942D01*
X290884Y262000D01*
X292999D01*
X294058Y260942D01*
Y257768D01*
Y259884D02*
X296173Y262000D01*
Y264116D02*
Y266232D01*
Y265174D01*
X289825D01*
X290884Y264116D01*
X507826Y125362D02*
X514174D01*
Y129594D01*
X507826Y135942D02*
Y131710D01*
X514174D01*
Y135942D01*
X511000Y131710D02*
Y133826D01*
X507826Y138058D02*
X514174D01*
Y141232D01*
X513116Y142290D01*
X508884D01*
X507826Y141232D01*
Y138058D01*
X514174Y148638D02*
Y144406D01*
X509942Y148638D01*
X508884D01*
X507826Y147580D01*
Y145464D01*
X508884Y144406D01*
X439826Y125420D02*
X446174D01*
Y129652D01*
X439826Y136000D02*
Y131768D01*
X446174D01*
Y136000D01*
X443000Y131768D02*
Y133884D01*
X439826Y138116D02*
X446174D01*
Y141290D01*
X445116Y142348D01*
X440884D01*
X439826Y141290D01*
Y138116D01*
X446174Y144464D02*
Y146580D01*
Y145522D01*
X439826D01*
X440884Y144464D01*
X116768Y193174D02*
Y186826D01*
X121000D01*
X123116D02*
X125232D01*
X124174D01*
Y193174D01*
X123116Y192116D01*
X88942Y249174D02*
X86826D01*
X87884D01*
Y243884D01*
X86826Y242826D01*
X85768D01*
X84710Y243884D01*
X95290Y242826D02*
X91058D01*
X95290Y247058D01*
Y248116D01*
X94232Y249174D01*
X92116D01*
X91058Y248116D01*
X645000Y163174D02*
X642884D01*
X643942D01*
Y157884D01*
X642884Y156826D01*
X641826D01*
X640768Y157884D01*
X647116Y156826D02*
X649232D01*
X648174D01*
Y163174D01*
X647116Y162116D01*
X245884Y262942D02*
X244826Y261884D01*
Y259768D01*
X245884Y258710D01*
X250116D01*
X251174Y259768D01*
Y261884D01*
X250116Y262942D01*
X251174Y268232D02*
X244826D01*
X248000Y265058D01*
Y269290D01*
X384106Y39000D02*
X385164Y40058D01*
Y42174D01*
X384106Y43232D01*
X379874D01*
X378816Y42174D01*
Y40058D01*
X379874Y39000D01*
X384106Y36884D02*
X385164Y35826D01*
Y33710D01*
X384106Y32652D01*
X383048D01*
X381990Y33710D01*
Y34768D01*
Y33710D01*
X380932Y32652D01*
X379874D01*
X378816Y33710D01*
Y35826D01*
X379874Y36884D01*
X369173Y39000D02*
X370231Y40058D01*
Y42174D01*
X369173Y43232D01*
X364941D01*
X363883Y42174D01*
Y40058D01*
X364941Y39000D01*
X363883Y32652D02*
Y36884D01*
X368115Y32652D01*
X369173D01*
X370231Y33710D01*
Y35826D01*
X369173Y36884D01*
X354116Y39000D02*
X355174Y40058D01*
Y42174D01*
X354116Y43232D01*
X349884D01*
X348826Y42174D01*
Y40058D01*
X349884Y39000D01*
X348826Y36884D02*
Y34768D01*
Y35826D01*
X355174D01*
X354116Y36884D01*
D11*
X139542Y115516D02*
Y144484D01*
X111475Y112474D02*
Y124666D01*
X102458D02*
X111475D01*
X102458D02*
Y135334D01*
X111475D01*
Y147526D01*
X130525D01*
Y144484D02*
Y147526D01*
Y144484D02*
X139542D01*
X130525Y112474D02*
Y115516D01*
X111475Y112474D02*
X130525D01*
Y115516D02*
X139542D01*
D12*
X509285Y104429D02*
X511571D01*
X509285D02*
X510428Y105571D01*
X511571Y104429D01*
X440285D02*
X442571D01*
X440285D02*
X441428Y105571D01*
X442571Y104429D01*
D13*
X90710Y87826D02*
Y94174D01*
X93884D01*
X94942Y93116D01*
Y91000D01*
X93884Y89942D01*
X90710D01*
X92826D02*
X94942Y87826D01*
X97058Y88884D02*
X98116Y87826D01*
X100232D01*
X101290Y88884D01*
Y93116D01*
X100232Y94174D01*
X98116D01*
X97058Y93116D01*
Y92058D01*
X98116Y91000D01*
X101290D01*
X224710Y56826D02*
Y63174D01*
X227884D01*
X228942Y62116D01*
Y60000D01*
X227884Y58942D01*
X224710D01*
X226826D02*
X228942Y56826D01*
X231058Y63174D02*
X235290D01*
Y62116D01*
X231058Y57884D01*
Y56826D01*
X129710Y87826D02*
Y94174D01*
X132884D01*
X133942Y93116D01*
Y91000D01*
X132884Y89942D01*
X129710D01*
X131826D02*
X133942Y87826D01*
X140290Y94174D02*
X138174Y93116D01*
X136058Y91000D01*
Y88884D01*
X137116Y87826D01*
X139232D01*
X140290Y88884D01*
Y89942D01*
X139232Y91000D01*
X136058D01*
D14*
X510469Y104770D02*
D03*
X441469D02*
D03*
D15*
X385000Y209377D02*
D03*
D16*
X657072Y81657D02*
D03*
D17*
X144500Y28500D02*
D03*
M02*
